(kicad_pcb
	(version 20260206)
	(generator "pcbnew")
	(generator_version "10.0")
	(general
		(thickness 1.6)
		(legacy_teardrops no)
	)
	(paper "A4")
	(title_block
		(title "9054_F0T_PDB_BD_GPU_F_V04_1213_1550_OCP.brd")
		(comment 1 "Grand Teton / footprints 375-378 of 608")
	)
	(layers
		(0 "F.Cu" signal "TOP")
		(4 "In1.Cu" signal "GND")
		(6 "In2.Cu" signal "IN1")
		(8 "In3.Cu" signal "GND1")
		(10 "In4.Cu" signal "VCC")
		(12 "In5.Cu" signal "VCC1")
		(14 "In6.Cu" signal "GND2")
		(16 "In7.Cu" signal "IN2")
		(18 "In8.Cu" signal "GND3")
		(2 "B.Cu" signal "BOTTOM")
		(9 "F.Adhes" user "F.Adhesive")
		(11 "B.Adhes" user "B.Adhesive")
		(13 "F.Paste" user "Package Geometry/Pastemask Top")
		(15 "B.Paste" user "Package Geometry/Pastemask Bottom")
		(5 "F.SilkS" user "Ref Des/Silkscreen Top")
		(7 "B.SilkS" user "Ref Des/Silkscreen Bottom")
		(1 "F.Mask" user "Board Geometry/Soldermask Top")
		(3 "B.Mask" user "Board Geometry/Soldermask Bottom")
		(17 "Dwgs.User" user "User.Drawings")
		(19 "Cmts.User" user "User.Comments")
		(21 "Eco1.User" user "User.Eco1")
		(23 "Eco2.User" user "User.Eco2")
		(25 "Edge.Cuts" user "Board Geometry/Outline")
		(27 "Margin" user)
		(31 "F.CrtYd" user "Package Geometry/Place Bound Top")
		(29 "B.CrtYd" user "Package Geometry/Place Bound Bottom")
		(35 "F.Fab" user "Ref Des/Assembly Top")
		(33 "B.Fab" user "Ref Des/Assembly Bottom")
	)
	(footprint ""
		(layer "F.Cu")
		(at 414.9344 -36.068)
		(property "Reference" "R423"
			(at 0 0 0)
			(layer "F.SilkS")
			(hide yes)
			(effects
				(font
					(size 1.27 1.27)
				)
			)
		)
		(property "Value" ""
			(at 0 0 0)
			(layer "F.Fab")
			(effects
				(font
					(size 1.27 1.27)
				)
			)
		)
		(duplicate_pad_numbers_are_jumpers no)
		(fp_line
			(start -0.7874 -0.4064)
			(end 0.7874 -0.4064)
			(stroke
				(width 0.1524)
				(type default)
			)
			(layer "F.SilkS")
		)
		(fp_line
			(start -0.7874 0.4064)
			(end -0.7874 -0.4064)
			(stroke
				(width 0.1524)
				(type default)
			)
			(layer "F.SilkS")
		)
		(fp_line
			(start 0.7874 -0.4064)
			(end 0.7874 0.4064)
			(stroke
				(width 0.1524)
				(type default)
			)
			(layer "F.SilkS")
		)
		(fp_line
			(start 0.7874 0.4064)
			(end -0.7874 0.4064)
			(stroke
				(width 0.1524)
				(type default)
			)
			(layer "F.SilkS")
		)
		(fp_line
			(start -0.67945 -0.305054)
			(end -0.12065 -0.305054)
			(stroke
				(width 0.1)
				(type default)
			)
			(layer "F.Fab")
		)
		(fp_line
			(start -0.67945 0.3048)
			(end -0.67945 -0.305054)
			(stroke
				(width 0.1)
				(type default)
			)
			(layer "F.Fab")
		)
		(fp_line
			(start -0.12065 -0.305054)
			(end -0.12065 -0.2794)
			(stroke
				(width 0.1)
				(type default)
			)
			(layer "F.Fab")
		)
		(fp_line
			(start -0.12065 -0.2794)
			(end 0.12065 -0.2794)
			(stroke
				(width 0.1)
				(type default)
			)
			(layer "F.Fab")
		)
		(fp_line
			(start -0.12065 0.2794)
			(end -0.12065 0.3048)
			(stroke
				(width 0.1)
				(type default)
			)
			(layer "F.Fab")
		)
		(fp_line
			(start -0.12065 0.3048)
			(end -0.67945 0.3048)
			(stroke
				(width 0.1)
				(type default)
			)
			(layer "F.Fab")
		)
		(fp_line
			(start 0.120396 0.2794)
			(end -0.12065 0.2794)
			(stroke
				(width 0.1)
				(type default)
			)
			(layer "F.Fab")
		)
		(fp_line
			(start 0.120396 0.3048)
			(end 0.120396 0.2794)
			(stroke
				(width 0.1)
				(type default)
			)
			(layer "F.Fab")
		)
		(fp_line
			(start 0.12065 -0.3048)
			(end 0.67945 -0.3048)
			(stroke
				(width 0.1)
				(type default)
			)
			(layer "F.Fab")
		)
		(fp_line
			(start 0.12065 -0.2794)
			(end 0.12065 -0.3048)
			(stroke
				(width 0.1)
				(type default)
			)
			(layer "F.Fab")
		)
		(fp_line
			(start 0.67945 -0.3048)
			(end 0.67945 0.3048)
			(stroke
				(width 0.1)
				(type default)
			)
			(layer "F.Fab")
		)
		(fp_line
			(start 0.67945 0.3048)
			(end 0.120396 0.3048)
			(stroke
				(width 0.1)
				(type default)
			)
			(layer "F.Fab")
		)
		(pad "1" smd circle
			(at -0.40005 0)
			(size 0 0)
			(layers "F.Cu" "F.Mask" "F.Paste")
			(net "PWRGD_P52V_HS2_4287_PG")
		)
		(pad "2" smd circle
			(at 0.40005 0)
			(size 0 0)
			(layers "F.Cu" "F.Mask" "F.Paste")
			(net "PWRGD_P52V_HS2_PG")
		)
	)
	(footprint ""
		(layer "F.Cu")
		(at 143.003778 -63.373 180)
		(property "Reference" "PR6976"
			(at 0.458978 -4.48437 0)
			(unlocked yes)
			(layer "F.SilkS")
			(effects
				(font
					(size 0.7874 0.5842)
					(thickness 0.1524)
				)
				(justify left)
			)
		)
		(property "Value" ""
			(at 0 0 180)
			(layer "F.Fab")
			(effects
				(font
					(size 1.27 1.27)
				)
			)
		)
		(duplicate_pad_numbers_are_jumpers no)
		(fp_line
			(start 3.9878 3.5814)
			(end -3.9878 3.5814)
			(stroke
				(width 0.1524)
				(type default)
			)
			(layer "F.SilkS")
		)
		(fp_line
			(start 3.9878 -3.5814)
			(end 3.9878 3.5814)
			(stroke
				(width 0.1524)
				(type default)
			)
			(layer "F.SilkS")
		)
		(fp_line
			(start -3.9878 3.5814)
			(end -3.9878 -3.5814)
			(stroke
				(width 0.1524)
				(type default)
			)
			(layer "F.SilkS")
		)
		(fp_line
			(start -3.9878 -3.5814)
			(end 3.9878 -3.5814)
			(stroke
				(width 0.1524)
				(type default)
			)
			(layer "F.SilkS")
		)
		(fp_line
			(start 3.5306 3.353054)
			(end -3.5306 3.353054)
			(stroke
				(width 0.1)
				(type default)
			)
			(layer "F.Fab")
		)
		(fp_line
			(start 3.5306 -3.353054)
			(end 3.5306 3.353054)
			(stroke
				(width 0.1)
				(type default)
			)
			(layer "F.Fab")
		)
		(fp_line
			(start -3.5306 3.353054)
			(end -3.5306 -3.353054)
			(stroke
				(width 0.1)
				(type default)
			)
			(layer "F.Fab")
		)
		(fp_line
			(start -3.5306 -3.353054)
			(end 3.5306 -3.353054)
			(stroke
				(width 0.1)
				(type default)
			)
			(layer "F.Fab")
		)
		(pad "1A" smd rect
			(at -2.249932 0)
			(size 3.2004 6.858)
			(layers "F.Cu" "F.Mask" "F.Paste")
			(net "P52V_2")
		)
		(pad "1B" smd rect
			(at -0.776732 0 180)
			(size 0.254 0.508)
			(layers "F.Cu" "F.Mask" "F.Paste")
			(net "P52V_HS2_SENSE_P_R1")
		)
		(pad "2A" smd rect
			(at 2.249932 0)
			(size 3.2004 6.858)
			(layers "F.Cu" "F.Mask" "F.Paste")
			(net "P52V_HS2_DRAIN_1")
		)
		(pad "2B" smd rect
			(at 0.776732 0 180)
			(size 0.254 0.508)
			(layers "F.Cu" "F.Mask" "F.Paste")
			(net "P52V_HS2_SENSE_N_R1")
		)
	)
	(footprint ""
		(layer "F.Cu")
		(at 265.9634 -49.149 -90)
		(property "Reference" "U22"
			(at -1.905 1.11633 90)
			(unlocked yes)
			(layer "F.SilkS")
			(effects
				(font
					(size 0.7874 0.5842)
					(thickness 0.1524)
				)
				(justify left)
			)
		)
		(property "Value" ""
			(at 0 0 270)
			(layer "F.Fab")
			(effects
				(font
					(size 1.27 1.27)
				)
			)
		)
		(duplicate_pad_numbers_are_jumpers no)
		(fp_line
			(start -1.603248 1.500124)
			(end -1.603248 -1.500124)
			(stroke
				(width 0.1524)
				(type default)
			)
			(layer "F.SilkS")
		)
		(fp_line
			(start 1.603248 1.500124)
			(end -1.603248 1.500124)
			(stroke
				(width 0.1524)
				(type default)
			)
			(layer "F.SilkS")
		)
		(fp_line
			(start -1.603248 -1.500124)
			(end 1.603248 -1.500124)
			(stroke
				(width 0.1524)
				(type default)
			)
			(layer "F.SilkS")
		)
		(fp_line
			(start 1.603248 -1.500124)
			(end 1.603248 1.500124)
			(stroke
				(width 0.1524)
				(type default)
			)
			(layer "F.SilkS")
		)
		(fp_line
			(start -0.700024 1.500124)
			(end 0.700024 1.500124)
			(stroke
				(width 0.1)
				(type default)
			)
			(layer "F.Fab")
		)
		(fp_line
			(start 0.700024 1.500124)
			(end 0.700024 0.219964)
			(stroke
				(width 0.1)
				(type default)
			)
			(layer "F.Fab")
		)
		(fp_line
			(start -1.249934 1.169924)
			(end -0.700024 1.169924)
			(stroke
				(width 0.1)
				(type default)
			)
			(layer "F.Fab")
		)
		(fp_line
			(start -0.700024 1.169924)
			(end -0.700024 1.500124)
			(stroke
				(width 0.1)
				(type default)
			)
			(layer "F.Fab")
		)
		(fp_line
			(start -1.249934 0.729996)
			(end -1.249934 1.169924)
			(stroke
				(width 0.1)
				(type default)
			)
			(layer "F.Fab")
		)
		(fp_line
			(start -0.6985 0.729996)
			(end -1.249934 0.729996)
			(stroke
				(width 0.1)
				(type default)
			)
			(layer "F.Fab")
		)
		(fp_line
			(start 0.700024 0.219964)
			(end 1.249934 0.219964)
			(stroke
				(width 0.1)
				(type default)
			)
			(layer "F.Fab")
		)
		(fp_line
			(start 1.249934 0.219964)
			(end 1.249934 -0.219964)
			(stroke
				(width 0.1)
				(type default)
			)
			(layer "F.Fab")
		)
		(fp_line
			(start 0.700024 -0.219964)
			(end 0.700024 -1.500124)
			(stroke
				(width 0.1)
				(type default)
			)
			(layer "F.Fab")
		)
		(fp_line
			(start 1.249934 -0.219964)
			(end 0.700024 -0.219964)
			(stroke
				(width 0.1)
				(type default)
			)
			(layer "F.Fab")
		)
		(fp_line
			(start -1.249934 -0.729996)
			(end -0.6985 -0.729996)
			(stroke
				(width 0.1)
				(type default)
			)
			(layer "F.Fab")
		)
		(fp_line
			(start -0.6985 -0.729996)
			(end -0.6985 0.729996)
			(stroke
				(width 0.1)
				(type default)
			)
			(layer "F.Fab")
		)
		(fp_line
			(start -1.249934 -1.169924)
			(end -1.249934 -0.729996)
			(stroke
				(width 0.1)
				(type default)
			)
			(layer "F.Fab")
		)
		(fp_line
			(start -0.700024 -1.169924)
			(end -1.249934 -1.169924)
			(stroke
				(width 0.1)
				(type default)
			)
			(layer "F.Fab")
		)
		(fp_line
			(start -0.700024 -1.500124)
			(end -0.700024 -1.169924)
			(stroke
				(width 0.1)
				(type default)
			)
			(layer "F.Fab")
		)
		(fp_line
			(start 0.700024 -1.500124)
			(end -0.700024 -1.500124)
			(stroke
				(width 0.1)
				(type default)
			)
			(layer "F.Fab")
		)
		(fp_rect
			(start -0.700024 1.500124)
			(end 0.700024 -1.500124)
			(stroke
				(width 0)
				(type default)
			)
			(fill no)
			(layer "F.Fab")
		)
		(pad "D" smd rect
			(at 0.999998 0 180)
			(size 0.8128 0.9144)
			(layers "F.Cu" "F.Mask" "F.Paste")
			(net "GPU_HSC1_BUF_EN_N")
		)
		(pad "G" smd rect
			(at -0.999998 -0.94996 180)
			(size 0.8128 0.9144)
			(layers "F.Cu" "F.Mask" "F.Paste")
			(net "GPU_HSC_BUF_EN")
		)
		(pad "S" smd rect
			(at -0.999998 0.94996 180)
			(size 0.8128 0.9144)
			(layers "F.Cu" "F.Mask" "F.Paste")
			(net "GND")
		)
	)
	(footprint ""
		(layer "F.Cu")
		(at 302.4124 -68.199 180)
		(property "Reference" "PR6963"
			(at 0 0 180)
			(layer "F.SilkS")
			(hide yes)
			(effects
				(font
					(size 1.27 1.27)
				)
			)
		)
		(property "Value" ""
			(at 0 0 180)
			(layer "F.Fab")
			(effects
				(font
					(size 1.27 1.27)
				)
			)
		)
		(duplicate_pad_numbers_are_jumpers no)
		(fp_line
			(start 1.2954 0.5842)
			(end -1.2954 0.5842)
			(stroke
				(width 0.1524)
				(type default)
			)
			(layer "F.SilkS")
		)
		(fp_line
			(start 1.2954 -0.5842)
			(end 1.2954 0.5842)
			(stroke
				(width 0.1524)
				(type default)
			)
			(layer "F.SilkS")
		)
		(fp_line
			(start -1.2954 0.5842)
			(end -1.2954 -0.5842)
			(stroke
				(width 0.1524)
				(type default)
			)
			(layer "F.SilkS")
		)
		(fp_line
			(start -1.2954 -0.5842)
			(end 1.2954 -0.5842)
			(stroke
				(width 0.1524)
				(type default)
			)
			(layer "F.SilkS")
		)
		(fp_line
			(start 1.1938 0.4064)
			(end 0.8636 0.4064)
			(stroke
				(width 0.1)
				(type default)
			)
			(layer "F.Fab")
		)
		(fp_line
			(start 1.1938 -0.406654)
			(end 1.1938 0.4064)
			(stroke
				(width 0.1)
				(type default)
			)
			(layer "F.Fab")
		)
		(fp_line
			(start 0.8636 0.4572)
			(end -0.8636 0.4572)
			(stroke
				(width 0.1)
				(type default)
			)
			(layer "F.Fab")
		)
		(fp_line
			(start 0.8636 0.4064)
			(end 0.8636 0.4572)
			(stroke
				(width 0.1)
				(type default)
			)
			(layer "F.Fab")
		)
		(fp_line
			(start 0.8636 -0.406654)
			(end 1.1938 -0.406654)
			(stroke
				(width 0.1)
				(type default)
			)
			(layer "F.Fab")
		)
		(fp_line
			(start 0.8636 -0.4572)
			(end 0.8636 -0.406654)
			(stroke
				(width 0.1)
				(type default)
			)
			(layer "F.Fab")
		)
		(fp_line
			(start -0.8636 0.4572)
			(end -0.8636 0.4318)
			(stroke
				(width 0.1)
				(type default)
			)
			(layer "F.Fab")
		)
		(fp_line
			(start -0.8636 0.4318)
			(end -0.8636 0.4064)
			(stroke
				(width 0.1)
				(type default)
			)
			(layer "F.Fab")
		)
		(fp_line
			(start -0.8636 0.4064)
			(end -1.1938 0.4064)
			(stroke
				(width 0.1)
				(type default)
			)
			(layer "F.Fab")
		)
		(fp_line
			(start -0.8636 -0.406654)
			(end -0.8636 -0.4572)
			(stroke
				(width 0.1)
				(type default)
			)
			(layer "F.Fab")
		)
		(fp_line
			(start -0.8636 -0.4572)
			(end 0.8636 -0.4572)
			(stroke
				(width 0.1)
				(type default)
			)
			(layer "F.Fab")
		)
		(fp_line
			(start -1.1938 0.4064)
			(end -1.1938 -0.406654)
			(stroke
				(width 0.1)
				(type default)
			)
			(layer "F.Fab")
		)
		(fp_line
			(start -1.1938 -0.406654)
			(end -0.8636 -0.406654)
			(stroke
				(width 0.1)
				(type default)
			)
			(layer "F.Fab")
		)
		(pad "1" smd rect
			(at -0.7366 0 90)
			(size 0.7112 0.8128)
			(layers "F.Cu" "F.Mask" "F.Paste")
			(net "P52V_HS_4287_ADC_P")
		)
		(pad "2" smd rect
			(at 0.7366 0 90)
			(size 0.7112 0.8128)
			(layers "F.Cu" "F.Mask" "F.Paste")
			(net "P52V_HS1_SENSE_P_R1")
		)
	)
)
